(kicad_pcb
	(version 20260206)
	(generator "pcbnew")
	(generator_version "10.0")
	(general
		(thickness 1.6)
		(legacy_teardrops no)
	)
	(paper "A4")
	(title_block
		(title "panther-plus-userver — 13130-1b_20150205.brd")
		(comment 1 "Honey Badger (Wiwynn) / footprints 974-981 of 1509")
	)
	(layers
		(0 "F.Cu" signal "TOP")
		(4 "In1.Cu" signal "L2")
		(6 "In2.Cu" signal "L3")
		(8 "In3.Cu" signal "L4")
		(10 "In4.Cu" signal "L5")
		(12 "In5.Cu" signal "L6")
		(14 "In6.Cu" signal "L7")
		(16 "In7.Cu" signal "L8")
		(18 "In8.Cu" signal "L9")
		(20 "In9.Cu" signal "L10")
		(22 "In10.Cu" signal "L11")
		(2 "B.Cu" signal "BOTTOM")
		(9 "F.Adhes" user "F.Adhesive")
		(11 "B.Adhes" user "B.Adhesive")
		(13 "F.Paste" user "Package Geometry/Pastemask Top")
		(15 "B.Paste" user "Package Geometry/Pastemask Bottom")
		(5 "F.SilkS" user "Ref Des/Silkscreen Top")
		(7 "B.SilkS" user "Ref Des/Silkscreen Bottom")
		(1 "F.Mask" user "Board Geometry/Soldermask Top")
		(3 "B.Mask" user "Board Geometry/Soldermask Bottom")
		(17 "Dwgs.User" user "User.Drawings")
		(19 "Cmts.User" user "User.Comments")
		(21 "Eco1.User" user "User.Eco1")
		(23 "Eco2.User" user "User.Eco2")
		(25 "Edge.Cuts" user "Board Geometry/Outline")
		(27 "Margin" user)
		(31 "F.CrtYd" user "Package Geometry/Place Bound Top")
		(29 "B.CrtYd" user "Package Geometry/Place Bound Bottom")
		(35 "F.Fab" user "Ref Des/Assembly Top")
		(33 "B.Fab" user "Ref Des/Assembly Bottom")
	)
	(footprint ""
		(layer "B.Cu")
		(at 47.371 -15.9004)
		(property "Reference" "R420"
			(at 0 0 0)
			(layer "B.SilkS")
			(hide yes)
			(effects
				(font
					(size 1.27 1.27)
				)
				(justify mirror)
			)
		)
		(property "Value" "33R2F-3-GP"
			(at -1.7907 -1.1176 0)
			(unlocked yes)
			(layer "B.Fab")
			(hide yes)
			(effects
				(font
					(size 1.016 1.016)
					(thickness 0.1524)
				)
				(justify mirror)
			)
		)
		(property "Device Type" "R402H16"
			(at -1.7907 -2.6416 0)
			(unlocked yes)
			(layer "B.Fab")
			(hide yes)
			(effects
				(font
					(size 1.016 1.016)
					(thickness 0.1524)
				)
				(justify mirror)
			)
		)
		(duplicate_pad_numbers_are_jumpers no)
		(fp_rect
			(start 0.381 0.8382)
			(end -0.381 -0.8382)
			(stroke
				(width 0)
				(type default)
			)
			(fill no)
			(layer "B.CrtYd")
		)
		(fp_rect
			(start 0.381 0.8382)
			(end -0.381 -0.8382)
			(stroke
				(width 0)
				(type default)
			)
			(fill no)
			(layer "B.Fab")
		)
		(pad "1" smd custom
			(at 0 -0.4318 180)
			(size 0.127 0.127)
			(layers "B.Cu" "B.Mask" "B.Paste")
			(net "CLK_100M_PCIE2_REFCLK_R_DN")
			(options
				(clearance outline)
				(anchor circle)
			)
			(primitives
				(gr_poly
					(pts
						(arc
							(start -0.2032 0.2794)
							(mid -0.239121 0.264521)
							(end -0.254 0.2286)
						)
						(arc
							(start -0.254 -0.2286)
							(mid -0.239121 -0.264521)
							(end -0.2032 -0.2794)
						)
						(arc
							(start 0.2032 -0.2794)
							(mid 0.239121 -0.264521)
							(end 0.254 -0.2286)
						)
						(arc
							(start 0.254 0.2286)
							(mid 0.239121 0.264521)
							(end 0.2032 0.2794)
						)
					)
					(width 0)
					(fill yes)
				)
			)
		)
		(pad "2" smd custom
			(at 0 0.4318 180)
			(size 0.127 0.127)
			(layers "B.Cu" "B.Mask" "B.Paste")
			(net "CLK_100M_PCIE2_REFCLK_DN")
			(options
				(clearance outline)
				(anchor circle)
			)
			(primitives
				(gr_poly
					(pts
						(arc
							(start -0.2032 0.2794)
							(mid -0.239121 0.264521)
							(end -0.254 0.2286)
						)
						(arc
							(start -0.254 -0.2286)
							(mid -0.239121 -0.264521)
							(end -0.2032 -0.2794)
						)
						(arc
							(start 0.2032 -0.2794)
							(mid 0.239121 -0.264521)
							(end 0.254 -0.2286)
						)
						(arc
							(start 0.254 0.2286)
							(mid 0.239121 0.264521)
							(end 0.2032 0.2794)
						)
					)
					(width 0)
					(fill yes)
				)
			)
		)
	)
	(footprint ""
		(layer "B.Cu")
		(at 74.3458 -19.9136)
		(property "Reference" "PC120"
			(at 0 0 0)
			(layer "B.SilkS")
			(hide yes)
			(effects
				(font
					(size 1.27 1.27)
				)
				(justify mirror)
			)
		)
		(property "Value" "SC22U6D3V5MX-2GP"
			(at 0 -4.9022 0)
			(unlocked yes)
			(layer "B.Fab")
			(hide yes)
			(effects
				(font
					(size 1.016 1.016)
					(thickness 0.1524)
				)
				(justify mirror)
			)
		)
		(property "Device Type" "C805H58"
			(at 0 -6.8072 0)
			(unlocked yes)
			(layer "B.Fab")
			(hide yes)
			(effects
				(font
					(size 1.016 1.016)
					(thickness 0.1524)
				)
				(justify mirror)
			)
		)
		(duplicate_pad_numbers_are_jumpers no)
		(fp_line
			(start -0.6096 0)
			(end 0.6096 0)
			(stroke
				(width 0.3048)
				(type default)
			)
			(layer "B.SilkS")
		)
		(fp_poly
			(pts
				(xy 0.9017 1.4351) (xy -0.9017 1.4351) (xy -0.9017 -1.4351) (xy 0.9017 -1.4351)
			)
			(stroke
				(width 0)
				(type default)
			)
			(fill no)
			(layer "B.CrtYd")
		)
		(fp_poly
			(pts
				(xy -0.9017 1.4351) (xy -0.9017 -1.4351) (xy 0.9017 -1.4351) (xy 0.9017 1.4351)
			)
			(stroke
				(width 0)
				(type default)
			)
			(fill no)
			(layer "B.Fab")
		)
		(pad "1" smd rect
			(at 0 -0.8382 180)
			(size 1.5494 0.9398)
			(layers "B.Cu" "B.Mask" "B.Paste")
			(net "VR_PVIN_P1V8_STBY")
		)
		(pad "2" smd rect
			(at 0 0.8382 180)
			(size 1.5494 0.9398)
			(layers "B.Cu" "B.Mask" "B.Paste")
			(net "GND")
		)
	)
	(footprint ""
		(layer "B.Cu")
		(at 90.678 -68.072)
		(property "Reference" "PC26"
			(at 0 0 0)
			(layer "B.SilkS")
			(hide yes)
			(effects
				(font
					(size 1.27 1.27)
				)
				(justify mirror)
			)
		)
		(property "Value" "SC10U6D3V5KX-4GP"
			(at 0.0762 -6.1214 0)
			(unlocked yes)
			(layer "B.Fab")
			(hide yes)
			(effects
				(font
					(size 1.016 1.016)
					(thickness 0.1524)
				)
				(justify mirror)
			)
		)
		(property "Device Type" "C805H58"
			(at 0.0762 -8.1534 0)
			(unlocked yes)
			(layer "B.Fab")
			(hide yes)
			(effects
				(font
					(size 1.016 1.016)
					(thickness 0.1524)
				)
				(justify mirror)
			)
		)
		(duplicate_pad_numbers_are_jumpers no)
		(fp_line
			(start -0.6096 0)
			(end 0.6096 0)
			(stroke
				(width 0.3048)
				(type default)
			)
			(layer "B.SilkS")
		)
		(fp_poly
			(pts
				(xy 0.9017 1.4351) (xy -0.9017 1.4351) (xy -0.9017 -1.4351) (xy 0.9017 -1.4351)
			)
			(stroke
				(width 0)
				(type default)
			)
			(fill no)
			(layer "B.CrtYd")
		)
		(fp_poly
			(pts
				(xy -0.9017 1.4351) (xy -0.9017 -1.4351) (xy 0.9017 -1.4351) (xy 0.9017 1.4351)
			)
			(stroke
				(width 0)
				(type default)
			)
			(fill no)
			(layer "B.Fab")
		)
		(pad "1" smd rect
			(at 0 -0.8382 180)
			(size 1.5494 0.9398)
			(layers "B.Cu" "B.Mask" "B.Paste")
			(net "VR_P1V1_PVIN")
		)
		(pad "2" smd rect
			(at 0 0.8382 180)
			(size 1.5494 0.9398)
			(layers "B.Cu" "B.Mask" "B.Paste")
			(net "GND")
		)
	)
	(footprint ""
		(layer "B.Cu")
		(at 101.1682 -44.6532 180)
		(property "Reference" "R309"
			(at 0 0 0)
			(layer "B.SilkS")
			(hide yes)
			(effects
				(font
					(size 1.27 1.27)
				)
				(justify mirror)
			)
		)
		(property "Value" "30D1R2F-L-GP"
			(at -0.064008 -3.993896 180)
			(unlocked yes)
			(layer "B.Fab")
			(hide yes)
			(effects
				(font
					(size 1.016 1.016)
					(thickness 0.1524)
				)
				(justify mirror)
			)
		)
		(property "Device Type" "R402H16"
			(at -0.064008 -5.517896 180)
			(unlocked yes)
			(layer "B.Fab")
			(hide yes)
			(effects
				(font
					(size 1.016 1.016)
					(thickness 0.1524)
				)
				(justify mirror)
			)
		)
		(duplicate_pad_numbers_are_jumpers no)
		(fp_rect
			(start 0.381 0.8382)
			(end -0.381 -0.8382)
			(stroke
				(width 0)
				(type default)
			)
			(fill no)
			(layer "B.CrtYd")
		)
		(fp_rect
			(start 0.381 0.8382)
			(end -0.381 -0.8382)
			(stroke
				(width 0)
				(type default)
			)
			(fill no)
			(layer "B.Fab")
		)
		(pad "1" smd custom
			(at 0 -0.4318)
			(size 0.127 0.127)
			(layers "B.Cu" "B.Mask" "B.Paste")
			(net "M_A_DQPU")
			(options
				(clearance outline)
				(anchor circle)
			)
			(primitives
				(gr_poly
					(pts
						(arc
							(start -0.2032 0.2794)
							(mid -0.239121 0.264521)
							(end -0.254 0.2286)
						)
						(arc
							(start -0.254 -0.2286)
							(mid -0.239121 -0.264521)
							(end -0.2032 -0.2794)
						)
						(arc
							(start 0.2032 -0.2794)
							(mid 0.239121 -0.264521)
							(end 0.254 -0.2286)
						)
						(arc
							(start 0.254 0.2286)
							(mid 0.239121 0.264521)
							(end 0.2032 0.2794)
						)
					)
					(width 0)
					(fill yes)
				)
			)
		)
		(pad "2" smd custom
			(at 0 0.4318)
			(size 0.127 0.127)
			(layers "B.Cu" "B.Mask" "B.Paste")
			(net "GND")
			(options
				(clearance outline)
				(anchor circle)
			)
			(primitives
				(gr_poly
					(pts
						(arc
							(start -0.2032 0.2794)
							(mid -0.239121 0.264521)
							(end -0.254 0.2286)
						)
						(arc
							(start -0.254 -0.2286)
							(mid -0.239121 -0.264521)
							(end -0.2032 -0.2794)
						)
						(arc
							(start 0.2032 -0.2794)
							(mid 0.239121 -0.264521)
							(end 0.254 -0.2286)
						)
						(arc
							(start 0.254 0.2286)
							(mid 0.239121 0.264521)
							(end 0.2032 0.2794)
						)
					)
					(width 0)
					(fill yes)
				)
			)
		)
	)
	(footprint ""
		(layer "B.Cu")
		(at 77.47 -61.8744)
		(property "Reference" "C85"
			(at 0 0 0)
			(layer "B.SilkS")
			(hide yes)
			(effects
				(font
					(size 1.27 1.27)
				)
				(justify mirror)
			)
		)
		(property "Value" "SCD1U16V2KX-3GP"
			(at -1.1811 -2.7051 0)
			(unlocked yes)
			(layer "B.Fab")
			(hide yes)
			(effects
				(font
					(size 1.016 1.016)
					(thickness 0.1524)
				)
				(justify mirror)
			)
		)
		(property "Device Type" "C402H22"
			(at -1.1811 -4.2291 0)
			(unlocked yes)
			(layer "B.Fab")
			(hide yes)
			(effects
				(font
					(size 1.016 1.016)
					(thickness 0.1524)
				)
				(justify mirror)
			)
		)
		(duplicate_pad_numbers_are_jumpers no)
		(fp_rect
			(start 0.381 0.7366)
			(end -0.381 -0.7366)
			(stroke
				(width 0)
				(type default)
			)
			(fill no)
			(layer "B.CrtYd")
		)
		(fp_rect
			(start 0.381 0.7366)
			(end -0.381 -0.7366)
			(stroke
				(width 0)
				(type default)
			)
			(fill no)
			(layer "B.Fab")
		)
		(pad "1" smd custom
			(at 0 -0.4572 180)
			(size 0.1143 0.1143)
			(layers "B.Cu" "B.Mask" "B.Paste")
			(net "PVCCP_SENSE")
			(options
				(clearance outline)
				(anchor circle)
			)
			(primitives
				(gr_poly
					(pts
						(arc
							(start -0.254 0.1778)
							(mid -0.239121 0.213721)
							(end -0.2032 0.2286)
						)
						(arc
							(start 0.2032 0.2286)
							(mid 0.239121 0.213721)
							(end 0.254 0.1778)
						)
						(arc
							(start 0.254 -0.1778)
							(mid 0.239121 -0.213721)
							(end 0.2032 -0.2286)
						)
						(arc
							(start -0.2032 -0.2286)
							(mid -0.239121 -0.213721)
							(end -0.254 -0.1778)
						)
					)
					(width 0)
					(fill yes)
				)
			)
		)
		(pad "2" smd custom
			(at 0 0.4572 180)
			(size 0.1143 0.1143)
			(layers "B.Cu" "B.Mask" "B.Paste")
			(net "GND")
			(options
				(clearance outline)
				(anchor circle)
			)
			(primitives
				(gr_poly
					(pts
						(arc
							(start -0.254 0.1778)
							(mid -0.239121 0.213721)
							(end -0.2032 0.2286)
						)
						(arc
							(start 0.2032 0.2286)
							(mid 0.239121 0.213721)
							(end 0.254 0.1778)
						)
						(arc
							(start 0.254 -0.1778)
							(mid 0.239121 -0.213721)
							(end 0.2032 -0.2286)
						)
						(arc
							(start -0.2032 -0.2286)
							(mid -0.239121 -0.213721)
							(end -0.254 -0.1778)
						)
					)
					(width 0)
					(fill yes)
				)
			)
		)
	)
	(footprint ""
		(layer "B.Cu")
		(at 119.38 -59.182 -90)
		(property "Reference" "C111"
			(at 0 0 90)
			(layer "B.SilkS")
			(hide yes)
			(effects
				(font
					(size 1.27 1.27)
				)
				(justify mirror)
			)
		)
		(property "Value" "SC10U6D3V3MX-GP"
			(at 0 -2.8194 270)
			(unlocked yes)
			(layer "B.Fab")
			(hide yes)
			(effects
				(font
					(size 1.016 1.016)
					(thickness 0.1524)
				)
				(justify mirror)
			)
		)
		(property "Device Type" "C603H38"
			(at 0 -4.3434 270)
			(unlocked yes)
			(layer "B.Fab")
			(hide yes)
			(effects
				(font
					(size 1.016 1.016)
					(thickness 0.1524)
				)
				(justify mirror)
			)
		)
		(duplicate_pad_numbers_are_jumpers no)
		(fp_line
			(start 0.4064 0)
			(end -0.4064 0)
			(stroke
				(width 0.2286)
				(type default)
			)
			(layer "B.SilkS")
		)
		(fp_rect
			(start 0.635 1.1811)
			(end -0.635 -1.1811)
			(stroke
				(width 0)
				(type default)
			)
			(fill no)
			(layer "B.CrtYd")
		)
		(fp_rect
			(start 0.635 1.1811)
			(end -0.635 -1.1811)
			(stroke
				(width 0)
				(type default)
			)
			(fill no)
			(layer "B.Fab")
		)
		(pad "1" smd custom
			(at 0 -0.6604 90)
			(size 0.19685 0.19685)
			(layers "B.Cu" "B.Mask" "B.Paste")
			(net "PV_VTT_DDR_A")
			(options
				(clearance outline)
				(anchor circle)
			)
			(primitives
				(gr_poly
					(pts
						(arc
							(start 0.508 0.2921)
							(mid 0.478242 0.363942)
							(end 0.4064 0.3937)
						)
						(arc
							(start -0.4064 0.3937)
							(mid -0.478242 0.363942)
							(end -0.508 0.2921)
						)
						(arc
							(start -0.508 -0.2921)
							(mid -0.478242 -0.363942)
							(end -0.4064 -0.3937)
						)
						(arc
							(start 0.4064 -0.3937)
							(mid 0.478242 -0.363942)
							(end 0.508 -0.2921)
						)
					)
					(width 0)
					(fill yes)
				)
			)
		)
		(pad "2" smd custom
			(at 0 0.6604 90)
			(size 0.19685 0.19685)
			(layers "B.Cu" "B.Mask" "B.Paste")
			(net "GND")
			(options
				(clearance outline)
				(anchor circle)
			)
			(primitives
				(gr_poly
					(pts
						(arc
							(start 0.508 0.2921)
							(mid 0.478242 0.363942)
							(end 0.4064 0.3937)
						)
						(arc
							(start -0.4064 0.3937)
							(mid -0.478242 0.363942)
							(end -0.508 0.2921)
						)
						(arc
							(start -0.508 -0.2921)
							(mid -0.478242 -0.363942)
							(end -0.4064 -0.3937)
						)
						(arc
							(start 0.4064 -0.3937)
							(mid 0.478242 -0.363942)
							(end 0.508 -0.2921)
						)
					)
					(width 0)
					(fill yes)
				)
			)
		)
	)
	(footprint ""
		(layer "B.Cu")
		(at 67.183 -30.5308 -90)
		(property "Reference" "C282"
			(at 0 0 90)
			(layer "B.SilkS")
			(hide yes)
			(effects
				(font
					(size 1.27 1.27)
				)
				(justify mirror)
			)
		)
		(property "Value" "SCD01U16V2KX-3GP"
			(at -1.1811 -2.7051 270)
			(unlocked yes)
			(layer "B.Fab")
			(hide yes)
			(effects
				(font
					(size 1.016 1.016)
					(thickness 0.1524)
				)
				(justify mirror)
			)
		)
		(property "Device Type" "C402H22"
			(at -1.1811 -4.2291 270)
			(unlocked yes)
			(layer "B.Fab")
			(hide yes)
			(effects
				(font
					(size 1.016 1.016)
					(thickness 0.1524)
				)
				(justify mirror)
			)
		)
		(duplicate_pad_numbers_are_jumpers no)
		(fp_rect
			(start 0.381 0.7366)
			(end -0.381 -0.7366)
			(stroke
				(width 0)
				(type default)
			)
			(fill no)
			(layer "B.CrtYd")
		)
		(fp_rect
			(start 0.381 0.7366)
			(end -0.381 -0.7366)
			(stroke
				(width 0)
				(type default)
			)
			(fill no)
			(layer "B.Fab")
		)
		(pad "1" smd custom
			(at 0 -0.4572 90)
			(size 0.1143 0.1143)
			(layers "B.Cu" "B.Mask" "B.Paste")
			(net "SATA3_RX_DP0")
			(options
				(clearance outline)
				(anchor circle)
			)
			(primitives
				(gr_poly
					(pts
						(arc
							(start -0.254 0.1778)
							(mid -0.239121 0.213721)
							(end -0.2032 0.2286)
						)
						(arc
							(start 0.2032 0.2286)
							(mid 0.239121 0.213721)
							(end 0.254 0.1778)
						)
						(arc
							(start 0.254 -0.1778)
							(mid 0.239121 -0.213721)
							(end 0.2032 -0.2286)
						)
						(arc
							(start -0.2032 -0.2286)
							(mid -0.239121 -0.213721)
							(end -0.254 -0.1778)
						)
					)
					(width 0)
					(fill yes)
				)
			)
		)
		(pad "2" smd custom
			(at 0 0.4572 90)
			(size 0.1143 0.1143)
			(layers "B.Cu" "B.Mask" "B.Paste")
			(net "SATA3_RX_C_DP0")
			(options
				(clearance outline)
				(anchor circle)
			)
			(primitives
				(gr_poly
					(pts
						(arc
							(start -0.254 0.1778)
							(mid -0.239121 0.213721)
							(end -0.2032 0.2286)
						)
						(arc
							(start 0.2032 0.2286)
							(mid 0.239121 0.213721)
							(end 0.254 0.1778)
						)
						(arc
							(start 0.254 -0.1778)
							(mid 0.239121 -0.213721)
							(end 0.2032 -0.2286)
						)
						(arc
							(start -0.2032 -0.2286)
							(mid -0.239121 -0.213721)
							(end -0.254 -0.1778)
						)
					)
					(width 0)
					(fill yes)
				)
			)
		)
	)
	(footprint ""
		(layer "B.Cu")
		(at 83.185 -21.59 90)
		(property "Reference" "PC194"
			(at 0 0 90)
			(layer "B.SilkS")
			(hide yes)
			(effects
				(font
					(size 1.27 1.27)
				)
				(justify mirror)
			)
		)
		(property "Value" "SC470P50V2KX-3GP"
			(at -1.1811 -2.7051 90)
			(unlocked yes)
			(layer "B.Fab")
			(hide yes)
			(effects
				(font
					(size 1.016 1.016)
					(thickness 0.1524)
				)
				(justify mirror)
			)
		)
		(property "Device Type" "C402H22"
			(at -1.1811 -4.2291 90)
			(unlocked yes)
			(layer "B.Fab")
			(hide yes)
			(effects
				(font
					(size 1.016 1.016)
					(thickness 0.1524)
				)
				(justify mirror)
			)
		)
		(duplicate_pad_numbers_are_jumpers no)
		(fp_rect
			(start 0.381 0.7366)
			(end -0.381 -0.7366)
			(stroke
				(width 0)
				(type default)
			)
			(fill no)
			(layer "B.CrtYd")
		)
		(fp_rect
			(start 0.381 0.7366)
			(end -0.381 -0.7366)
			(stroke
				(width 0)
				(type default)
			)
			(fill no)
			(layer "B.Fab")
		)
		(pad "1" smd custom
			(at 0 -0.4572 270)
			(size 0.1143 0.1143)
			(layers "B.Cu" "B.Mask" "B.Paste")
			(net "GND")
			(options
				(clearance outline)
				(anchor circle)
			)
			(primitives
				(gr_poly
					(pts
						(arc
							(start -0.254 0.1778)
							(mid -0.239121 0.213721)
							(end -0.2032 0.2286)
						)
						(arc
							(start 0.2032 0.2286)
							(mid 0.239121 0.213721)
							(end 0.254 0.1778)
						)
						(arc
							(start 0.254 -0.1778)
							(mid 0.239121 -0.213721)
							(end 0.2032 -0.2286)
						)
						(arc
							(start -0.2032 -0.2286)
							(mid -0.239121 -0.213721)
							(end -0.254 -0.1778)
						)
					)
					(width 0)
					(fill yes)
				)
			)
		)
		(pad "2" smd custom
			(at 0 0.4572 270)
			(size 0.1143 0.1143)
			(layers "B.Cu" "B.Mask" "B.Paste")
			(net "TPS74801_1V35_SS")
			(options
				(clearance outline)
				(anchor circle)
			)
			(primitives
				(gr_poly
					(pts
						(arc
							(start -0.254 0.1778)
							(mid -0.239121 0.213721)
							(end -0.2032 0.2286)
						)
						(arc
							(start 0.2032 0.2286)
							(mid 0.239121 0.213721)
							(end 0.254 0.1778)
						)
						(arc
							(start 0.254 -0.1778)
							(mid 0.239121 -0.213721)
							(end 0.2032 -0.2286)
						)
						(arc
							(start -0.2032 -0.2286)
							(mid -0.239121 -0.213721)
							(end -0.254 -0.1778)
						)
					)
					(width 0)
					(fill yes)
				)
			)
		)
	)
)
